# T6G (Grand Teton) — schematic netlist excerpt (pin names and nets, part order shuffled) for the footprints in the layout excerpt that follows; sources: Cadence DE-HDL packaged netlist, KiCad conversion of 04192023_DAF0TMB3IC0_F0TG_MB_C_brd_V02_OCP.brd

R1529  Q_RES  1K 1% EMPTY  pkg 0402LF  page 77 : A = PVDD18_S5_P0 ; B = SPI_CPU0_D3
PC145_7  Q_CAP  0.1UF 25V 10% X7R  pkg 0402  page 205 : A = PVDDCR_CPU1_P0_VCCS ; B = GND

(kicad_pcb
	(version 20260206)
	(generator "pcbnew")
	(generator_version "10.0")
	(general
		(thickness 1.6)
		(legacy_teardrops no)
	)
	(paper "A4")
	(title_block
		(title "04192023_DAF0TMB3IC0_F0TG_MB_C_brd_V02_OCP.brd")
		(comment 1 "Grand Teton / footprints 1229-1230 of 8354")
	)
	(layers
		(0 "F.Cu" signal "TOP")
		(4 "In1.Cu" signal "GND")
		(6 "In2.Cu" signal "IN1")
		(8 "In3.Cu" signal "GND1")
		(10 "In4.Cu" signal "IN2")
		(12 "In5.Cu" signal "GND2")
		(14 "In6.Cu" signal "IN3")
		(16 "In7.Cu" signal "GND3")
		(18 "In8.Cu" signal "VCC")
		(20 "In9.Cu" signal "VCC1")
		(22 "In10.Cu" signal "GND4")
		(24 "In11.Cu" signal "IN4")
		(26 "In12.Cu" signal "GND5")
		(28 "In13.Cu" signal "IN5")
		(30 "In14.Cu" signal "GND6")
		(32 "In15.Cu" signal "IN6")
		(34 "In16.Cu" signal "GND7")
		(2 "B.Cu" signal "BOTTOM")
		(9 "F.Adhes" user "F.Adhesive")
		(11 "B.Adhes" user "B.Adhesive")
		(13 "F.Paste" user "Package Geometry/Pastemask Top")
		(15 "B.Paste" user "Package Geometry/Pastemask Bottom")
		(5 "F.SilkS" user "Ref Des/Silkscreen Top")
		(7 "B.SilkS" user "Ref Des/Silkscreen Bottom")
		(1 "F.Mask" user "Board Geometry/Soldermask Top")
		(3 "B.Mask" user "Board Geometry/Soldermask Bottom")
		(17 "Dwgs.User" user "User.Drawings")
		(19 "Cmts.User" user "User.Comments")
		(21 "Eco1.User" user "User.Eco1")
		(23 "Eco2.User" user "User.Eco2")
		(25 "Edge.Cuts" user "Board Geometry/Outline")
		(27 "Margin" user)
		(31 "F.CrtYd" user "Package Geometry/Place Bound Top")
		(29 "B.CrtYd" user "Package Geometry/Place Bound Bottom")
		(35 "F.Fab" user "Ref Des/Assembly Top")
		(33 "B.Fab" user "Ref Des/Assembly Bottom")
	)
	(footprint ""
		(layer "F.Cu")
		(at 264.986516 -138.321796 180)
		(property "Reference" "R1529"
			(at 0 0 180)
			(layer "F.SilkS")
			(hide yes)
			(effects
				(font
					(size 1.27 1.27)
				)
			)
		)
		(property "Value" ""
			(at 0 0 180)
			(layer "F.Fab")
			(effects
				(font
					(size 1.27 1.27)
				)
			)
		)
		(duplicate_pad_numbers_are_jumpers no)
		(fp_line
			(start 0.7874 0.4064)
			(end -0.7874 0.4064)
			(stroke
				(width 0.1524)
				(type default)
			)
			(layer "F.SilkS")
		)
		(fp_line
			(start 0.7874 -0.4064)
			(end 0.7874 0.4064)
			(stroke
				(width 0.1524)
				(type default)
			)
			(layer "F.SilkS")
		)
		(fp_line
			(start -0.7874 0.4064)
			(end -0.7874 -0.4064)
			(stroke
				(width 0.1524)
				(type default)
			)
			(layer "F.SilkS")
		)
		(fp_line
			(start -0.7874 -0.4064)
			(end 0.7874 -0.4064)
			(stroke
				(width 0.1524)
				(type default)
			)
			(layer "F.SilkS")
		)
		(fp_line
			(start 0.67945 0.3048)
			(end 0.120396 0.3048)
			(stroke
				(width 0.1)
				(type default)
			)
			(layer "F.Fab")
		)
		(fp_line
			(start 0.67945 -0.3048)
			(end 0.67945 0.3048)
			(stroke
				(width 0.1)
				(type default)
			)
			(layer "F.Fab")
		)
		(fp_line
			(start 0.12065 -0.2794)
			(end 0.12065 -0.3048)
			(stroke
				(width 0.1)
				(type default)
			)
			(layer "F.Fab")
		)
		(fp_line
			(start 0.12065 -0.3048)
			(end 0.67945 -0.3048)
			(stroke
				(width 0.1)
				(type default)
			)
			(layer "F.Fab")
		)
		(fp_line
			(start 0.120396 0.3048)
			(end 0.120396 0.2794)
			(stroke
				(width 0.1)
				(type default)
			)
			(layer "F.Fab")
		)
		(fp_line
			(start 0.120396 0.2794)
			(end -0.12065 0.2794)
			(stroke
				(width 0.1)
				(type default)
			)
			(layer "F.Fab")
		)
		(fp_line
			(start -0.12065 0.3048)
			(end -0.67945 0.3048)
			(stroke
				(width 0.1)
				(type default)
			)
			(layer "F.Fab")
		)
		(fp_line
			(start -0.12065 0.2794)
			(end -0.12065 0.3048)
			(stroke
				(width 0.1)
				(type default)
			)
			(layer "F.Fab")
		)
		(fp_line
			(start -0.12065 -0.2794)
			(end 0.12065 -0.2794)
			(stroke
				(width 0.1)
				(type default)
			)
			(layer "F.Fab")
		)
		(fp_line
			(start -0.12065 -0.305054)
			(end -0.12065 -0.2794)
			(stroke
				(width 0.1)
				(type default)
			)
			(layer "F.Fab")
		)
		(fp_line
			(start -0.67945 0.3048)
			(end -0.67945 -0.305054)
			(stroke
				(width 0.1)
				(type default)
			)
			(layer "F.Fab")
		)
		(fp_line
			(start -0.67945 -0.305054)
			(end -0.12065 -0.305054)
			(stroke
				(width 0.1)
				(type default)
			)
			(layer "F.Fab")
		)
		(pad "1" smd circle
			(at -0.40005 0 180)
			(size 0 0)
			(layers "F.Cu" "F.Mask" "F.Paste")
			(net "PVDD18_S5_P0")
		)
		(pad "2" smd circle
			(at 0.40005 0 180)
			(size 0 0)
			(layers "F.Cu" "F.Mask" "F.Paste")
			(net "SPI_CPU0_D3")
		)
	)
	(footprint ""
		(layer "F.Cu")
		(at 297.670982 -351.573846 90)
		(property "Reference" "PC145_7"
			(at 0 0 90)
			(layer "F.SilkS")
			(hide yes)
			(effects
				(font
					(size 1.27 1.27)
				)
			)
		)
		(property "Value" ""
			(at 0 0 90)
			(layer "F.Fab")
			(effects
				(font
					(size 1.27 1.27)
				)
			)
		)
		(duplicate_pad_numbers_are_jumpers no)
		(fp_line
			(start 0.7874 -0.4064)
			(end 0.7874 0.4064)
			(stroke
				(width 0.1524)
				(type default)
			)
			(layer "F.SilkS")
		)
		(fp_line
			(start -0.7874 -0.4064)
			(end 0.7874 -0.4064)
			(stroke
				(width 0.1524)
				(type default)
			)
			(layer "F.SilkS")
		)
		(fp_line
			(start 0.7874 0.4064)
			(end -0.7874 0.4064)
			(stroke
				(width 0.1524)
				(type default)
			)
			(layer "F.SilkS")
		)
		(fp_line
			(start -0.7874 0.4064)
			(end -0.7874 -0.4064)
			(stroke
				(width 0.1524)
				(type default)
			)
			(layer "F.SilkS")
		)
		(fp_line
			(start -0.12065 -0.305054)
			(end -0.12065 -0.2794)
			(stroke
				(width 0.1)
				(type default)
			)
			(layer "F.Fab")
		)
		(fp_line
			(start -0.67945 -0.305054)
			(end -0.12065 -0.305054)
			(stroke
				(width 0.1)
				(type default)
			)
			(layer "F.Fab")
		)
		(fp_line
			(start 0.67945 -0.3048)
			(end 0.67945 0.3048)
			(stroke
				(width 0.1)
				(type default)
			)
			(layer "F.Fab")
		)
		(fp_line
			(start 0.12065 -0.3048)
			(end 0.67945 -0.3048)
			(stroke
				(width 0.1)
				(type default)
			)
			(layer "F.Fab")
		)
		(fp_line
			(start 0.12065 -0.2794)
			(end 0.12065 -0.3048)
			(stroke
				(width 0.1)
				(type default)
			)
			(layer "F.Fab")
		)
		(fp_line
			(start -0.12065 -0.2794)
			(end 0.12065 -0.2794)
			(stroke
				(width 0.1)
				(type default)
			)
			(layer "F.Fab")
		)
		(fp_line
			(start 0.120396 0.2794)
			(end -0.12065 0.2794)
			(stroke
				(width 0.1)
				(type default)
			)
			(layer "F.Fab")
		)
		(fp_line
			(start -0.12065 0.2794)
			(end -0.12065 0.3048)
			(stroke
				(width 0.1)
				(type default)
			)
			(layer "F.Fab")
		)
		(fp_line
			(start 0.67945 0.3048)
			(end 0.120396 0.3048)
			(stroke
				(width 0.1)
				(type default)
			)
			(layer "F.Fab")
		)
		(fp_line
			(start 0.120396 0.3048)
			(end 0.120396 0.2794)
			(stroke
				(width 0.1)
				(type default)
			)
			(layer "F.Fab")
		)
		(fp_line
			(start -0.12065 0.3048)
			(end -0.67945 0.3048)
			(stroke
				(width 0.1)
				(type default)
			)
			(layer "F.Fab")
		)
		(fp_line
			(start -0.67945 0.3048)
			(end -0.67945 -0.305054)
			(stroke
				(width 0.1)
				(type default)
			)
			(layer "F.Fab")
		)
		(pad "1" smd circle
			(at -0.40005 0 90)
			(size 0 0)
			(layers "F.Cu" "F.Mask" "F.Paste")
			(net "PVDDCR_CPU1_P0_VCCS")
		)
		(pad "2" smd circle
			(at 0.40005 0 90)
			(size 0 0)
			(layers "F.Cu" "F.Mask" "F.Paste")
			(net "GND")
		)
	)
)
